# GPS_MODULE_NEO-M9N_BOM_sma-ver.xlsx — 844-XXXXX-XX-RevX1 (bom)
| Designator | Fitted | Quantity | Manufacturer | Manufacturer Part Number 1 | Supplier 1 | Supplier Part Number 1 | Footprint | Description | Comment |
| C4 | Fitted | 1 | Yageo | CC0402JRNPO9BN470 | Digi-Key | 311-1021-1-ND | c0402 | 0402 47 pF 50 V ±5 % Tolerance NP0 SMT Multilayer Ceramic Capacitor | 47pF 50V 0402 |
| R1, R5, R7, R8 | Fitted | 4 | Yageo | RC0402JR-070RL | Digi-Key | 311-0.0JRCT-ND | r0402 | RES SMD 0 OHM JUMPER 1/16W 0402 | 0 ohm 0402 |
| R4 | Fitted | 1 | Yageo | SR0603FR-7T10RL | Digi-Key | YAG5824CT-ND | r0603 | Res Surge Chip Thick Film 0603 10 Ohm 1% 1/4W ±200ppm/°C Molded Paper T/R | 10 OHM 1/4W 0603 |
| R6, R9, R10 | Not Fitted | 0 | Yageo | RC0402JR-070RL | Digi-Key | 311-0.0JRCT-ND | r0402 | RES SMD 0 OHM JUMPER 1/16W 0402 | DNI 0 ohm 0402 |
| LED1, LED2 | Fitted | 2 | Vishay Lite-On | LTST-C190KGKT | Digi-Key | 160-1435-1-ND | led0603 | LED High-Power Uni-Color Green 574nm 2-Pin Chip LED T/R | Green |
| U1 | Fitted | 1 | u-blox | NEO-M9N-00B | Digi-Key | 672-NEO-M9N-00BCT-ND | IC_NEO-M9N | GNSS module, Flash, TCXO, SAW, LNA, LCC, 12x16 mm Professional Grade | NEO-M9N-00B |
| R2, R3 | Fitted | 2 | TE Connectivity | CRGP0402F10K | Digi-Key | A130367CT-ND | r0402 | Res Thick Film 0402 10K Ohm 1% 0.125W(1/8W) ±100ppm/°C Pad SMD T/R | 10K 1/8W 0402 |
| J1 | Fitted | 1 | Sullins | NRPN042MAMS-RC | Digi-Key | S6009-04-ND | CONN_NRPN042MAMS-RC | Dual Row 8 Position 2 mm Pitch Surface Mount Header | NRPN042MAMS-RC 2MM |
| C2 | Fitted | 1 | Samsung | CL05B104KP5NNNC | Digi-Key | 1276-1002-1-ND | c0402 | CL05 Series 0.1 uF 10 V ±10 % Tolerance X7R SMT Multilayer Ceramic Capacitor | 100nF 10V 0402 |
| C1 | Fitted | 1 | Murata | GRM155R70J105KA12J | Digi-Key | 490-13339-1-ND | c0402 | 0402 1 uF 6.3 V ±10% Tolerance X7R Multilayer Ceramic Capacitor | 1uF 6V3 0402 |
| C3, C5 | Fitted | 2 | Murata | GCM155R71H103KA55D | Digi-Key | 490-4762-1-ND | c0402 | CAP CER 10000PF 50V X7R 0402 | 10nF 50V 0402 |
| L1 | Fitted | 1 | Murata | LQG15HS27NJ02D | Digi-Key | 490-2628-1-ND | L0402 | Inductor RF Chip Multi-Layer 27nH 5% 100MHz 8Q-Factor Air 300mA 460mOhm DCR 0402 Paper T/R | 27nH 300mA 460mohm 0402 |
| Q1 | Fitted | 1 | Diodes | DMG2302UKQ-7 | Digi-Key | 31-DMG2302UKQ-7CT-ND | SOT23 | N-Channel 20 V 2.8A (Ta) 660mW (Ta) Surface Mount SOT-23-3 | DMG2302UKQ-7 |
| J2 | Fitted | 1 | Bel Cinch | 142-0711-301 | Digi-Key | J717-ND | CONN_131-3711-301 | Rf Coaxial Board Mount Connector | SMA_142-0711-301 |
